(kicad_pcb
	(version 20260206)
	(generator "pcbnew")
	(generator_version "10.0")
	(general
		(thickness 1.6)
		(legacy_teardrops no)
	)
	(paper "A4")
	(title_block
		(title "Wiwynn_Tioga_Pass_MB.brd")
		(comment 1 "Tioga Pass / footprints 1395-1402 of 4770")
	)
	(layers
		(0 "F.Cu" signal "TOP")
		(4 "In1.Cu" signal "L2GND")
		(6 "In2.Cu" signal "L3")
		(8 "In3.Cu" signal "L4GND")
		(10 "In4.Cu" signal "L5")
		(12 "In5.Cu" signal "L6GND")
		(14 "In6.Cu" signal "L7VCC")
		(16 "In7.Cu" signal "L8VCC")
		(18 "In8.Cu" signal "L9GND")
		(20 "In9.Cu" signal "L10")
		(22 "In10.Cu" signal "L11GND")
		(24 "In11.Cu" signal "L12")
		(26 "In12.Cu" signal "L13GND")
		(2 "B.Cu" signal "BOTTOM")
		(9 "F.Adhes" user "F.Adhesive")
		(11 "B.Adhes" user "B.Adhesive")
		(13 "F.Paste" user "Package Geometry/Pastemask Top")
		(15 "B.Paste" user "Package Geometry/Pastemask Bottom")
		(5 "F.SilkS" user "Ref Des/Silkscreen Top")
		(7 "B.SilkS" user "Ref Des/Silkscreen Bottom")
		(1 "F.Mask" user "Board Geometry/Soldermask Top")
		(3 "B.Mask" user "Board Geometry/Soldermask Bottom")
		(17 "Dwgs.User" user "User.Drawings")
		(19 "Cmts.User" user "User.Comments")
		(21 "Eco1.User" user "User.Eco1")
		(23 "Eco2.User" user "User.Eco2")
		(25 "Edge.Cuts" user "Board Geometry/Outline")
		(27 "Margin" user)
		(31 "F.CrtYd" user "Package Geometry/Place Bound Top")
		(29 "B.CrtYd" user "Package Geometry/Place Bound Bottom")
		(35 "F.Fab" user "Ref Des/Assembly Top")
		(33 "B.Fab" user "Ref Des/Assembly Bottom")
	)
	(footprint ""
		(layer "F.Cu")
		(at 480.845876 3.820668 -90)
		(property "Reference" "R9G17"
			(at 0 0 270)
			(layer "F.SilkS")
			(hide yes)
			(effects
				(font
					(size 1.27 1.27)
				)
			)
		)
		(property "Value" ""
			(at 0 0 270)
			(layer "F.Fab")
			(effects
				(font
					(size 1.27 1.27)
				)
			)
		)
		(duplicate_pad_numbers_are_jumpers no)
		(fp_poly
			(pts
				(xy -0.2794 -0.1016) (xy 0.2794 -0.1016) (xy 0.2794 0.9906) (xy -0.2794 0.9906)
			)
			(stroke
				(width 0)
				(type default)
			)
			(fill no)
			(layer "F.CrtYd")
		)
		(fp_line
			(start -0.2794 0.9906)
			(end 0.2794 0.9906)
			(stroke
				(width 0.1)
				(type default)
			)
			(layer "F.Fab")
		)
		(fp_line
			(start 0.2794 0.9906)
			(end 0.2794 -0.1016)
			(stroke
				(width 0.1)
				(type default)
			)
			(layer "F.Fab")
		)
		(fp_line
			(start -0.2794 -0.1016)
			(end -0.2794 0.9906)
			(stroke
				(width 0.1)
				(type default)
			)
			(layer "F.Fab")
		)
		(fp_line
			(start 0.2794 -0.1016)
			(end -0.2794 -0.1016)
			(stroke
				(width 0.1)
				(type default)
			)
			(layer "F.Fab")
		)
		(pad "1" smd rect
			(at 0 0 270)
			(size 0.508 0.508)
			(layers "F.Cu" "F.Mask" "F.Paste")
			(net "NIC_SET_N_MDI_2_DN")
		)
		(pad "2" smd rect
			(at 0 0.889 270)
			(size 0.508 0.508)
			(layers "F.Cu" "F.Mask" "F.Paste")
			(net "NIC_MDI_SPRV_RJ45_2_R_DN")
		)
		(zone
			(layer "F.Cu")
			(hatch none 0.5)
			(connect_pads
				(clearance 0)
			)
			(min_thickness 0.25)
			(keepout
				(tracks not_allowed)
				(vias allowed)
				(pads allowed)
				(copperpour not_allowed)
				(footprints allowed)
			)
			(placement
				(enabled no)
				(sheetname "")
			)
			(fill
				(thermal_gap 0.5)
				(thermal_bridge_width 0.5)
				(island_removal_mode 0)
			)
			(polygon
				(pts
					(xy 480.210876 3.566668) (xy 480.210876 4.074668) (xy 480.591876 4.074668) (xy 480.591876 3.566668)
				)
			)
		)
		(zone
			(layer "F.Cu")
			(hatch none 0.5)
			(connect_pads
				(clearance 0)
			)
			(min_thickness 0.25)
			(keepout
				(tracks allowed)
				(vias not_allowed)
				(pads allowed)
				(copperpour not_allowed)
				(footprints allowed)
			)
			(placement
				(enabled no)
				(sheetname "")
			)
			(fill
				(thermal_gap 0.5)
				(thermal_bridge_width 0.5)
				(island_removal_mode 0)
			)
			(polygon
				(pts
					(xy 480.591876 3.566668) (xy 480.591876 4.074668) (xy 480.210876 4.074668) (xy 480.210876 3.566668)
				)
			)
		)
	)
	(footprint ""
		(layer "F.Cu")
		(at 175.26 -149.3012 -90)
		(property "Reference" "R4A5"
			(at 0 0 270)
			(layer "F.SilkS")
			(hide yes)
			(effects
				(font
					(size 1.27 1.27)
				)
			)
		)
		(property "Value" ""
			(at 0 0 270)
			(layer "F.Fab")
			(effects
				(font
					(size 1.27 1.27)
				)
			)
		)
		(duplicate_pad_numbers_are_jumpers no)
		(fp_rect
			(start 0.2794 -0.1016)
			(end -0.2794 0.9906)
			(stroke
				(width 0)
				(type default)
			)
			(fill no)
			(layer "F.CrtYd")
		)
		(fp_line
			(start -0.2794 0.9906)
			(end 0.2794 0.9906)
			(stroke
				(width 0.1)
				(type default)
			)
			(layer "F.Fab")
		)
		(fp_line
			(start 0.2794 0.9906)
			(end 0.2794 -0.1016)
			(stroke
				(width 0.1)
				(type default)
			)
			(layer "F.Fab")
		)
		(fp_line
			(start -0.2794 -0.1016)
			(end -0.2794 0.9906)
			(stroke
				(width 0.1)
				(type default)
			)
			(layer "F.Fab")
		)
		(fp_line
			(start 0.2794 -0.1016)
			(end -0.2794 -0.1016)
			(stroke
				(width 0.1)
				(type default)
			)
			(layer "F.Fab")
		)
		(pad "1" smd rect
			(at 0 0 270)
			(size 0.508 0.508)
			(layers "F.Cu" "F.Mask" "F.Paste")
			(net "P3V3")
		)
		(pad "2" smd rect
			(at 0 0.889 270)
			(size 0.508 0.508)
			(layers "F.Cu" "F.Mask" "F.Paste")
			(net "PWRGD_PVTT_KLM_CPU1_R")
		)
		(zone
			(layer "F.Cu")
			(hatch none 0.5)
			(connect_pads
				(clearance 0)
			)
			(min_thickness 0.25)
			(keepout
				(tracks not_allowed)
				(vias allowed)
				(pads allowed)
				(copperpour not_allowed)
				(footprints allowed)
			)
			(placement
				(enabled no)
				(sheetname "")
			)
			(fill
				(thermal_gap 0.5)
				(thermal_bridge_width 0.5)
				(island_removal_mode 0)
			)
			(polygon
				(pts
					(xy 175.006 -149.0472) (xy 175.006 -149.5552) (xy 174.625 -149.5552) (xy 174.625 -149.0472)
				)
			)
		)
		(zone
			(layer "F.Cu")
			(hatch none 0.5)
			(connect_pads
				(clearance 0)
			)
			(min_thickness 0.25)
			(keepout
				(tracks allowed)
				(vias not_allowed)
				(pads allowed)
				(copperpour not_allowed)
				(footprints allowed)
			)
			(placement
				(enabled no)
				(sheetname "")
			)
			(fill
				(thermal_gap 0.5)
				(thermal_bridge_width 0.5)
				(island_removal_mode 0)
			)
			(polygon
				(pts
					(xy 175.006 -149.0472) (xy 175.006 -149.5552) (xy 174.625 -149.5552) (xy 174.625 -149.0472)
				)
			)
		)
	)
	(footprint ""
		(layer "F.Cu")
		(at 93.30944 -81.573116)
		(property "Reference" "C2D9"
			(at 0 0 0)
			(layer "F.SilkS")
			(hide yes)
			(effects
				(font
					(size 1.27 1.27)
				)
			)
		)
		(property "Value" ""
			(at 0 0 0)
			(layer "F.Fab")
			(effects
				(font
					(size 1.27 1.27)
				)
			)
		)
		(duplicate_pad_numbers_are_jumpers no)
		(fp_poly
			(pts
				(xy -0.4953 -0.2032) (xy 0.4953 -0.2032) (xy 0.4953 1.6002) (xy -0.4953 1.6002)
			)
			(stroke
				(width 0)
				(type default)
			)
			(fill no)
			(layer "F.CrtYd")
		)
		(fp_line
			(start -0.4953 -0.2032)
			(end 0.4953 -0.2032)
			(stroke
				(width 0.1)
				(type default)
			)
			(layer "F.Fab")
		)
		(fp_line
			(start -0.4953 1.6002)
			(end -0.4953 -0.2032)
			(stroke
				(width 0.1)
				(type default)
			)
			(layer "F.Fab")
		)
		(fp_line
			(start 0.4953 -0.2032)
			(end 0.4953 1.6002)
			(stroke
				(width 0.1)
				(type default)
			)
			(layer "F.Fab")
		)
		(fp_line
			(start 0.4953 1.6002)
			(end -0.4953 1.6002)
			(stroke
				(width 0.1)
				(type default)
			)
			(layer "F.Fab")
		)
		(pad "1" smd rect
			(at 0 0)
			(size 0.762 0.889)
			(layers "F.Cu" "F.Mask" "F.Paste")
			(net "PVSA_CPU1")
		)
		(pad "2" smd rect
			(at 0 1.397)
			(size 0.762 0.889)
			(layers "F.Cu" "F.Mask" "F.Paste")
			(net "GND")
		)
		(zone
			(layer "F.Cu")
			(hatch none 0.5)
			(connect_pads
				(clearance 0)
			)
			(min_thickness 0.25)
			(keepout
				(tracks not_allowed)
				(vias allowed)
				(pads allowed)
				(copperpour not_allowed)
				(footprints allowed)
			)
			(placement
				(enabled no)
				(sheetname "")
			)
			(fill
				(thermal_gap 0.5)
				(thermal_bridge_width 0.5)
				(island_removal_mode 0)
			)
			(polygon
				(pts
					(xy 92.92844 -81.128616) (xy 93.69044 -81.128616) (xy 93.69044 -80.620616) (xy 92.92844 -80.620616)
				)
			)
		)
	)
	(footprint ""
		(layer "F.Cu")
		(at 171.958 -14.5796 -90)
		(property "Reference" "L4G1"
			(at 4.953 6.95833 90)
			(unlocked yes)
			(layer "F.SilkS")
			(effects
				(font
					(size 0.7874 0.5842)
					(thickness 0.1524)
				)
				(justify left)
			)
		)
		(property "Value" ""
			(at 0 0 270)
			(layer "F.Fab")
			(effects
				(font
					(size 1.27 1.27)
				)
			)
		)
		(duplicate_pad_numbers_are_jumpers no)
		(fp_line
			(start -3.4036 6.1341)
			(end -3.4036 -0.6731)
			(stroke
				(width 0.1524)
				(type default)
			)
			(layer "F.SilkS")
		)
		(fp_line
			(start -2.5654 6.1341)
			(end -3.4036 6.1341)
			(stroke
				(width 0.1524)
				(type default)
			)
			(layer "F.SilkS")
		)
		(fp_line
			(start 3.4036 6.1341)
			(end 2.5654 6.1341)
			(stroke
				(width 0.1524)
				(type default)
			)
			(layer "F.SilkS")
		)
		(fp_line
			(start -3.4036 -0.6731)
			(end -2.5654 -0.6731)
			(stroke
				(width 0.1524)
				(type default)
			)
			(layer "F.SilkS")
		)
		(fp_line
			(start 2.5654 -0.6731)
			(end 3.4036 -0.6731)
			(stroke
				(width 0.1524)
				(type default)
			)
			(layer "F.SilkS")
		)
		(fp_line
			(start 3.4036 -0.6731)
			(end 3.4036 6.1341)
			(stroke
				(width 0.1524)
				(type default)
			)
			(layer "F.SilkS")
		)
		(fp_rect
			(start 3.4036 6.1341)
			(end -3.4036 -0.6731)
			(stroke
				(width 0)
				(type default)
			)
			(fill no)
			(layer "F.CrtYd")
		)
		(fp_line
			(start -3.4036 6.1341)
			(end -3.4036 -0.6731)
			(stroke
				(width 0.1)
				(type default)
			)
			(layer "F.Fab")
		)
		(fp_line
			(start 3.4036 6.1341)
			(end -3.4036 6.1341)
			(stroke
				(width 0.1)
				(type default)
			)
			(layer "F.Fab")
		)
		(fp_line
			(start -3.4036 -0.6731)
			(end 3.4036 -0.6731)
			(stroke
				(width 0.1)
				(type default)
			)
			(layer "F.Fab")
		)
		(fp_line
			(start 3.4036 -0.6731)
			(end 3.4036 6.1341)
			(stroke
				(width 0.1)
				(type default)
			)
			(layer "F.Fab")
		)
		(pad "1" smd rect
			(at 0 0 270)
			(size 3.556 3.175)
			(layers "F.Cu" "F.Mask" "F.Paste")
			(net "VR_PVPP_GHJ_PHASE")
		)
		(pad "2" smd rect
			(at 0 5.461 270)
			(size 3.556 3.175)
			(layers "F.Cu" "F.Mask" "F.Paste")
			(net "PVPP_GHJ")
		)
	)
	(footprint ""
		(layer "F.Cu")
		(at 176.276 -141.1605 90)
		(property "Reference" "R4A7"
			(at 0 0 90)
			(layer "F.SilkS")
			(hide yes)
			(effects
				(font
					(size 1.27 1.27)
				)
			)
		)
		(property "Value" ""
			(at 0 0 90)
			(layer "F.Fab")
			(effects
				(font
					(size 1.27 1.27)
				)
			)
		)
		(duplicate_pad_numbers_are_jumpers no)
		(fp_poly
			(pts
				(xy -0.2794 -0.1016) (xy 0.2794 -0.1016) (xy 0.2794 0.9906) (xy -0.2794 0.9906)
			)
			(stroke
				(width 0)
				(type default)
			)
			(fill no)
			(layer "F.CrtYd")
		)
		(fp_line
			(start 0.2794 -0.1016)
			(end -0.2794 -0.1016)
			(stroke
				(width 0.1)
				(type default)
			)
			(layer "F.Fab")
		)
		(fp_line
			(start -0.2794 -0.1016)
			(end -0.2794 0.9906)
			(stroke
				(width 0.1)
				(type default)
			)
			(layer "F.Fab")
		)
		(fp_line
			(start 0.2794 0.9906)
			(end 0.2794 -0.1016)
			(stroke
				(width 0.1)
				(type default)
			)
			(layer "F.Fab")
		)
		(fp_line
			(start -0.2794 0.9906)
			(end 0.2794 0.9906)
			(stroke
				(width 0.1)
				(type default)
			)
			(layer "F.Fab")
		)
		(pad "1" smd rect
			(at 0 0 90)
			(size 0.508 0.508)
			(layers "F.Cu" "F.Mask" "F.Paste")
			(net "VR_PVPP_KLM_SNUB")
		)
		(pad "2" smd rect
			(at 0 0.889 90)
			(size 0.508 0.508)
			(layers "F.Cu" "F.Mask" "F.Paste")
			(net "GND")
		)
		(zone
			(layer "F.Cu")
			(hatch none 0.5)
			(connect_pads
				(clearance 0)
			)
			(min_thickness 0.25)
			(keepout
				(tracks allowed)
				(vias not_allowed)
				(pads allowed)
				(copperpour not_allowed)
				(footprints allowed)
			)
			(placement
				(enabled no)
				(sheetname "")
			)
			(fill
				(thermal_gap 0.5)
				(thermal_bridge_width 0.5)
				(island_removal_mode 0)
			)
			(polygon
				(pts
					(xy 176.53 -140.9065) (xy 176.53 -141.4145) (xy 176.911 -141.4145) (xy 176.911 -140.9065)
				)
			)
		)
		(zone
			(layer "F.Cu")
			(hatch none 0.5)
			(connect_pads
				(clearance 0)
			)
			(min_thickness 0.25)
			(keepout
				(tracks not_allowed)
				(vias allowed)
				(pads allowed)
				(copperpour not_allowed)
				(footprints allowed)
			)
			(placement
				(enabled no)
				(sheetname "")
			)
			(fill
				(thermal_gap 0.5)
				(thermal_bridge_width 0.5)
				(island_removal_mode 0)
			)
			(polygon
				(pts
					(xy 176.911 -140.9065) (xy 176.911 -141.4145) (xy 176.53 -141.4145) (xy 176.53 -140.9065)
				)
			)
		)
	)
	(footprint ""
		(layer "F.Cu")
		(at 426.5295 -129.794 -90)
		(property "Reference" "R8B7"
			(at 0 0 270)
			(layer "F.SilkS")
			(hide yes)
			(effects
				(font
					(size 1.27 1.27)
				)
			)
		)
		(property "Value" ""
			(at 0 0 270)
			(layer "F.Fab")
			(effects
				(font
					(size 1.27 1.27)
				)
			)
		)
		(duplicate_pad_numbers_are_jumpers no)
		(fp_poly
			(pts
				(xy -0.2794 -0.1016) (xy 0.2794 -0.1016) (xy 0.2794 0.9906) (xy -0.2794 0.9906)
			)
			(stroke
				(width 0)
				(type default)
			)
			(fill no)
			(layer "F.CrtYd")
		)
		(fp_line
			(start -0.2794 0.9906)
			(end 0.2794 0.9906)
			(stroke
				(width 0.1)
				(type default)
			)
			(layer "F.Fab")
		)
		(fp_line
			(start 0.2794 0.9906)
			(end 0.2794 -0.1016)
			(stroke
				(width 0.1)
				(type default)
			)
			(layer "F.Fab")
		)
		(fp_line
			(start -0.2794 -0.1016)
			(end -0.2794 0.9906)
			(stroke
				(width 0.1)
				(type default)
			)
			(layer "F.Fab")
		)
		(fp_line
			(start 0.2794 -0.1016)
			(end -0.2794 -0.1016)
			(stroke
				(width 0.1)
				(type default)
			)
			(layer "F.Fab")
		)
		(pad "1" smd rect
			(at 0 0 270)
			(size 0.508 0.508)
			(layers "F.Cu" "F.Mask" "F.Paste")
			(net "PVPP_ABC")
		)
		(pad "2" smd rect
			(at 0 0.889 270)
			(size 0.508 0.508)
			(layers "F.Cu" "F.Mask" "F.Paste")
			(net "SMB_HFI0_CPU0_LVC2_SDA")
		)
		(zone
			(layer "F.Cu")
			(hatch none 0.5)
			(connect_pads
				(clearance 0)
			)
			(min_thickness 0.25)
			(keepout
				(tracks not_allowed)
				(vias allowed)
				(pads allowed)
				(copperpour not_allowed)
				(footprints allowed)
			)
			(placement
				(enabled no)
				(sheetname "")
			)
			(fill
				(thermal_gap 0.5)
				(thermal_bridge_width 0.5)
				(island_removal_mode 0)
			)
			(polygon
				(pts
					(xy 425.8945 -130.048) (xy 425.8945 -129.54) (xy 426.2755 -129.54) (xy 426.2755 -130.048)
				)
			)
		)
		(zone
			(layer "F.Cu")
			(hatch none 0.5)
			(connect_pads
				(clearance 0)
			)
			(min_thickness 0.25)
			(keepout
				(tracks allowed)
				(vias not_allowed)
				(pads allowed)
				(copperpour not_allowed)
				(footprints allowed)
			)
			(placement
				(enabled no)
				(sheetname "")
			)
			(fill
				(thermal_gap 0.5)
				(thermal_bridge_width 0.5)
				(island_removal_mode 0)
			)
			(polygon
				(pts
					(xy 426.2755 -130.048) (xy 426.2755 -129.54) (xy 425.8945 -129.54) (xy 425.8945 -130.048)
				)
			)
		)
	)
	(footprint ""
		(layer "F.Cu")
		(at 433.1335 -11.4046 180)
		(property "Reference" "C6W14"
			(at -0.8382 -0.67818 180)
			(unlocked yes)
			(layer "F.SilkS")
			(effects
				(font
					(size 0.4064 0.254)
					(thickness 0.1524)
				)
				(justify left)
			)
		)
		(property "Value" ""
			(at 0 0 180)
			(layer "F.Fab")
			(effects
				(font
					(size 1.27 1.27)
				)
			)
		)
		(duplicate_pad_numbers_are_jumpers no)
		(fp_poly
			(pts
				(xy 0.3048 -0.1016) (xy 0.3048 0.9906) (xy -0.3048 0.9906) (xy -0.3048 -0.1016)
			)
			(stroke
				(width 0)
				(type default)
			)
			(fill no)
			(layer "F.CrtYd")
		)
		(fp_line
			(start 0.3048 0.9906)
			(end 0.3048 -0.1016)
			(stroke
				(width 0.1)
				(type default)
			)
			(layer "F.Fab")
		)
		(fp_line
			(start 0.3048 -0.1016)
			(end -0.3048 -0.1016)
			(stroke
				(width 0.1)
				(type default)
			)
			(layer "F.Fab")
		)
		(fp_line
			(start -0.3048 0.9906)
			(end 0.3048 0.9906)
			(stroke
				(width 0.1)
				(type default)
			)
			(layer "F.Fab")
		)
		(fp_line
			(start -0.3048 -0.1016)
			(end -0.3048 0.9906)
			(stroke
				(width 0.1)
				(type default)
			)
			(layer "F.Fab")
		)
		(pad "1" smd rect
			(at 0 0 180)
			(size 0.508 0.508)
			(layers "F.Cu" "F.Mask" "F.Paste")
			(net "P3V3_STBY")
		)
		(pad "2" smd rect
			(at 0 0.889 180)
			(size 0.508 0.508)
			(layers "F.Cu" "F.Mask" "F.Paste")
			(net "GND")
		)
		(zone
			(layer "F.Cu")
			(hatch none 0.5)
			(connect_pads
				(clearance 0)
			)
			(min_thickness 0.25)
			(keepout
				(tracks not_allowed)
				(vias allowed)
				(pads allowed)
				(copperpour not_allowed)
				(footprints allowed)
			)
			(placement
				(enabled no)
				(sheetname "")
			)
			(fill
				(thermal_gap 0.5)
				(thermal_bridge_width 0.5)
				(island_removal_mode 0)
			)
			(polygon
				(pts
					(xy 433.3875 -12.0396) (xy 432.8795 -12.0396) (xy 432.8795 -11.6586) (xy 433.3875 -11.6586)
				)
			)
		)
		(zone
			(layer "F.Cu")
			(hatch none 0.5)
			(connect_pads
				(clearance 0)
			)
			(min_thickness 0.25)
			(keepout
				(tracks allowed)
				(vias not_allowed)
				(pads allowed)
				(copperpour not_allowed)
				(footprints allowed)
			)
			(placement
				(enabled no)
				(sheetname "")
			)
			(fill
				(thermal_gap 0.5)
				(thermal_bridge_width 0.5)
				(island_removal_mode 0)
			)
			(polygon
				(pts
					(xy 433.3875 -11.6586) (xy 432.8795 -11.6586) (xy 432.8795 -12.0396) (xy 433.3875 -12.0396)
				)
			)
		)
	)
	(footprint ""
		(layer "F.Cu")
		(at 336.509868 -130.455162 90)
		(property "Reference" "C7B30"
			(at 0 0 90)
			(layer "F.SilkS")
			(hide yes)
			(effects
				(font
					(size 1.27 1.27)
				)
			)
		)
		(property "Value" ""
			(at 0 0 90)
			(layer "F.Fab")
			(effects
				(font
					(size 1.27 1.27)
				)
			)
		)
		(duplicate_pad_numbers_are_jumpers no)
		(fp_poly
			(pts
				(xy -0.4953 -0.2032) (xy 0.4953 -0.2032) (xy 0.4953 1.6002) (xy -0.4953 1.6002)
			)
			(stroke
				(width 0)
				(type default)
			)
			(fill no)
			(layer "F.CrtYd")
		)
		(fp_line
			(start 0.4953 -0.2032)
			(end 0.4953 1.6002)
			(stroke
				(width 0.1)
				(type default)
			)
			(layer "F.Fab")
		)
		(fp_line
			(start -0.4953 -0.2032)
			(end 0.4953 -0.2032)
			(stroke
				(width 0.1)
				(type default)
			)
			(layer "F.Fab")
		)
		(fp_line
			(start 0.4953 1.6002)
			(end -0.4953 1.6002)
			(stroke
				(width 0.1)
				(type default)
			)
			(layer "F.Fab")
		)
		(fp_line
			(start -0.4953 1.6002)
			(end -0.4953 -0.2032)
			(stroke
				(width 0.1)
				(type default)
			)
			(layer "F.Fab")
		)
		(pad "1" smd rect
			(at 0 0 90)
			(size 0.762 0.889)
			(layers "F.Cu" "F.Mask" "F.Paste")
			(net "VR_PVPP_DEF_PHASE")
		)
		(pad "2" smd rect
			(at 0 1.397 90)
			(size 0.762 0.889)
			(layers "F.Cu" "F.Mask" "F.Paste")
			(net "VR_PVPP_DEF_BOOT_R")
		)
		(zone
			(layer "F.Cu")
			(hatch none 0.5)
			(connect_pads
				(clearance 0)
			)
			(min_thickness 0.25)
			(keepout
				(tracks not_allowed)
				(vias allowed)
				(pads allowed)
				(copperpour not_allowed)
				(footprints allowed)
			)
			(placement
				(enabled no)
				(sheetname "")
			)
			(fill
				(thermal_gap 0.5)
				(thermal_bridge_width 0.5)
				(island_removal_mode 0)
			)
			(polygon
				(pts
					(xy 336.954368 -130.074162) (xy 336.954368 -130.836162) (xy 337.462368 -130.836162) (xy 337.462368 -130.074162)
				)
			)
		)
	)
)
